(kicad_pcb
	(version 20260206)
	(generator "pcbnew")
	(generator_version "10.0")
	(general
		(thickness 1.6)
		(legacy_teardrops no)
	)
	(paper "A4")
	(title_block
		(title "panther-plus-userver — 13130-1b_20150205.brd")
		(comment 1 "Honey Badger (Wiwynn) / footprints 565-572 of 1509")
	)
	(layers
		(0 "F.Cu" signal "TOP")
		(4 "In1.Cu" signal "L2")
		(6 "In2.Cu" signal "L3")
		(8 "In3.Cu" signal "L4")
		(10 "In4.Cu" signal "L5")
		(12 "In5.Cu" signal "L6")
		(14 "In6.Cu" signal "L7")
		(16 "In7.Cu" signal "L8")
		(18 "In8.Cu" signal "L9")
		(20 "In9.Cu" signal "L10")
		(22 "In10.Cu" signal "L11")
		(2 "B.Cu" signal "BOTTOM")
		(9 "F.Adhes" user "F.Adhesive")
		(11 "B.Adhes" user "B.Adhesive")
		(13 "F.Paste" user "Package Geometry/Pastemask Top")
		(15 "B.Paste" user "Package Geometry/Pastemask Bottom")
		(5 "F.SilkS" user "Ref Des/Silkscreen Top")
		(7 "B.SilkS" user "Ref Des/Silkscreen Bottom")
		(1 "F.Mask" user "Board Geometry/Soldermask Top")
		(3 "B.Mask" user "Board Geometry/Soldermask Bottom")
		(17 "Dwgs.User" user "User.Drawings")
		(19 "Cmts.User" user "User.Comments")
		(21 "Eco1.User" user "User.Eco1")
		(23 "Eco2.User" user "User.Eco2")
		(25 "Edge.Cuts" user "Board Geometry/Outline")
		(27 "Margin" user)
		(31 "F.CrtYd" user "Package Geometry/Place Bound Top")
		(29 "B.CrtYd" user "Package Geometry/Place Bound Bottom")
		(35 "F.Fab" user "Ref Des/Assembly Top")
		(33 "B.Fab" user "Ref Des/Assembly Bottom")
	)
	(footprint ""
		(layer "F.Cu")
		(at 27.178 -68.199 -90)
		(property "Reference" "PR64"
			(at 0 0 270)
			(layer "F.SilkS")
			(hide yes)
			(effects
				(font
					(size 1.27 1.27)
				)
			)
		)
		(property "Value" "3K3R3F-GP"
			(at -0.0254 -2.0193 270)
			(unlocked yes)
			(layer "F.Fab")
			(hide yes)
			(effects
				(font
					(size 1.016 1.016)
					(thickness 0.1524)
				)
			)
		)
		(property "Device Type" "R603H22"
			(at -0.0254 -3.5433 270)
			(unlocked yes)
			(layer "F.Fab")
			(hide yes)
			(effects
				(font
					(size 1.016 1.016)
					(thickness 0.1524)
				)
			)
		)
		(duplicate_pad_numbers_are_jumpers no)
		(fp_line
			(start -0.2032 0)
			(end -0.4191 0)
			(stroke
				(width 0.2032)
				(type default)
			)
			(layer "F.SilkS")
		)
		(fp_line
			(start 0.4318 0)
			(end 0.2032 0)
			(stroke
				(width 0.2032)
				(type default)
			)
			(layer "F.SilkS")
		)
		(fp_rect
			(start -0.635 1.1811)
			(end 0.635 -1.1811)
			(stroke
				(width 0)
				(type default)
			)
			(fill no)
			(layer "F.CrtYd")
		)
		(fp_rect
			(start -0.635 1.1811)
			(end 0.635 -1.1811)
			(stroke
				(width 0)
				(type default)
			)
			(fill no)
			(layer "F.Fab")
		)
		(pad "1" smd custom
			(at 0 -0.6604 270)
			(size 0.19685 0.19685)
			(layers "F.Cu" "F.Mask" "F.Paste")
			(net "P12V")
			(options
				(clearance outline)
				(anchor circle)
			)
			(primitives
				(gr_poly
					(pts
						(arc
							(start 0.508 -0.2921)
							(mid 0.478242 -0.363942)
							(end 0.4064 -0.3937)
						)
						(arc
							(start -0.4064 -0.3937)
							(mid -0.478242 -0.363942)
							(end -0.508 -0.2921)
						)
						(arc
							(start -0.508 0.2921)
							(mid -0.478242 0.363942)
							(end -0.4064 0.3937)
						)
						(arc
							(start 0.4064 0.3937)
							(mid 0.478242 0.363942)
							(end 0.508 0.2921)
						)
					)
					(width 0)
					(fill yes)
				)
			)
		)
		(pad "2" smd custom
			(at 0 0.6604 270)
			(size 0.19685 0.19685)
			(layers "F.Cu" "F.Mask" "F.Paste")
			(net "VCCP_Z")
			(options
				(clearance outline)
				(anchor circle)
			)
			(primitives
				(gr_poly
					(pts
						(arc
							(start 0.508 -0.2921)
							(mid 0.478242 -0.363942)
							(end 0.4064 -0.3937)
						)
						(arc
							(start -0.4064 -0.3937)
							(mid -0.478242 -0.363942)
							(end -0.508 -0.2921)
						)
						(arc
							(start -0.508 0.2921)
							(mid -0.478242 0.363942)
							(end -0.4064 0.3937)
						)
						(arc
							(start 0.4064 0.3937)
							(mid 0.478242 0.363942)
							(end 0.508 0.2921)
						)
					)
					(width 0)
					(fill yes)
				)
			)
		)
	)
	(footprint ""
		(layer "F.Cu")
		(at 148.082 -59.182)
		(property "Reference" "C369"
			(at 0 0 0)
			(layer "F.SilkS")
			(hide yes)
			(effects
				(font
					(size 1.27 1.27)
				)
			)
		)
		(property "Value" "SC47U6D3V5MX-1-GP"
			(at 0 -4.9022 0)
			(unlocked yes)
			(layer "F.Fab")
			(hide yes)
			(effects
				(font
					(size 1.016 1.016)
					(thickness 0.1524)
				)
			)
		)
		(property "Device Type" "C805H54"
			(at 0 -6.8072 0)
			(unlocked yes)
			(layer "F.Fab")
			(hide yes)
			(effects
				(font
					(size 1.016 1.016)
					(thickness 0.1524)
				)
			)
		)
		(duplicate_pad_numbers_are_jumpers no)
		(fp_line
			(start 0.6096 0)
			(end -0.6096 0)
			(stroke
				(width 0.3048)
				(type default)
			)
			(layer "F.SilkS")
		)
		(fp_poly
			(pts
				(xy -0.9017 1.4351) (xy 0.9017 1.4351) (xy 0.9017 -1.4351) (xy -0.9017 -1.4351)
			)
			(stroke
				(width 0)
				(type default)
			)
			(fill no)
			(layer "F.CrtYd")
		)
		(fp_poly
			(pts
				(xy 0.9017 1.4351) (xy 0.9017 -1.4351) (xy -0.9017 -1.4351) (xy -0.9017 1.4351)
			)
			(stroke
				(width 0)
				(type default)
			)
			(fill no)
			(layer "F.Fab")
		)
		(pad "1" smd rect
			(at 0 -0.8382)
			(size 1.5494 0.9398)
			(layers "F.Cu" "F.Mask" "F.Paste")
			(net "PV_VDDR")
		)
		(pad "2" smd rect
			(at 0 0.8382)
			(size 1.5494 0.9398)
			(layers "F.Cu" "F.Mask" "F.Paste")
			(net "GND")
		)
	)
	(footprint ""
		(layer "F.Cu")
		(at 169.672 -38.989 -90)
		(property "Reference" "PR226"
			(at 0 0 270)
			(layer "F.SilkS")
			(hide yes)
			(effects
				(font
					(size 1.27 1.27)
				)
			)
		)
		(property "Value" "0R3J-6-GP"
			(at -0.0254 -2.0193 270)
			(unlocked yes)
			(layer "F.Fab")
			(hide yes)
			(effects
				(font
					(size 1.016 1.016)
					(thickness 0.1524)
				)
			)
		)
		(property "Device Type" "R603H22"
			(at -0.0254 -3.5433 270)
			(unlocked yes)
			(layer "F.Fab")
			(hide yes)
			(effects
				(font
					(size 1.016 1.016)
					(thickness 0.1524)
				)
			)
		)
		(duplicate_pad_numbers_are_jumpers no)
		(fp_line
			(start -0.2032 0)
			(end -0.4191 0)
			(stroke
				(width 0.2032)
				(type default)
			)
			(layer "F.SilkS")
		)
		(fp_line
			(start 0.4318 0)
			(end 0.2032 0)
			(stroke
				(width 0.2032)
				(type default)
			)
			(layer "F.SilkS")
		)
		(fp_rect
			(start -0.635 1.1811)
			(end 0.635 -1.1811)
			(stroke
				(width 0)
				(type default)
			)
			(fill no)
			(layer "F.CrtYd")
		)
		(fp_rect
			(start -0.635 1.1811)
			(end 0.635 -1.1811)
			(stroke
				(width 0)
				(type default)
			)
			(fill no)
			(layer "F.Fab")
		)
		(pad "1" smd custom
			(at 0 -0.6604 270)
			(size 0.19685 0.19685)
			(layers "F.Cu" "F.Mask" "F.Paste")
			(net "P2V5_STBY_OUT")
			(options
				(clearance outline)
				(anchor circle)
			)
			(primitives
				(gr_poly
					(pts
						(arc
							(start 0.508 -0.2921)
							(mid 0.478242 -0.363942)
							(end 0.4064 -0.3937)
						)
						(arc
							(start -0.4064 -0.3937)
							(mid -0.478242 -0.363942)
							(end -0.508 -0.2921)
						)
						(arc
							(start -0.508 0.2921)
							(mid -0.478242 0.363942)
							(end -0.4064 0.3937)
						)
						(arc
							(start 0.4064 0.3937)
							(mid 0.478242 0.363942)
							(end 0.508 0.2921)
						)
					)
					(width 0)
					(fill yes)
				)
			)
		)
		(pad "2" smd custom
			(at 0 0.6604 270)
			(size 0.19685 0.19685)
			(layers "F.Cu" "F.Mask" "F.Paste")
			(net "P2V5_STBY")
			(options
				(clearance outline)
				(anchor circle)
			)
			(primitives
				(gr_poly
					(pts
						(arc
							(start 0.508 -0.2921)
							(mid 0.478242 -0.363942)
							(end 0.4064 -0.3937)
						)
						(arc
							(start -0.4064 -0.3937)
							(mid -0.478242 -0.363942)
							(end -0.508 -0.2921)
						)
						(arc
							(start -0.508 0.2921)
							(mid -0.478242 0.363942)
							(end -0.4064 0.3937)
						)
						(arc
							(start 0.4064 0.3937)
							(mid 0.478242 0.363942)
							(end 0.508 0.2921)
						)
					)
					(width 0)
					(fill yes)
				)
			)
		)
	)
	(footprint ""
		(layer "F.Cu")
		(at 182.9308 -29.5656 90)
		(property "Reference" "PC108"
			(at 0 0 90)
			(layer "F.SilkS")
			(hide yes)
			(effects
				(font
					(size 1.27 1.27)
				)
			)
		)
		(property "Value" "SC1KP50V2KX-1GP"
			(at 1.8923 -1.2065 90)
			(unlocked yes)
			(layer "F.Fab")
			(hide yes)
			(effects
				(font
					(size 1.016 1.016)
					(thickness 0.1524)
				)
			)
		)
		(property "Device Type" "C402H22"
			(at 1.8923 -2.7305 90)
			(unlocked yes)
			(layer "F.Fab")
			(hide yes)
			(effects
				(font
					(size 1.016 1.016)
					(thickness 0.1524)
				)
			)
		)
		(duplicate_pad_numbers_are_jumpers no)
		(fp_rect
			(start -0.381 0.7366)
			(end 0.381 -0.7366)
			(stroke
				(width 0)
				(type default)
			)
			(fill no)
			(layer "F.CrtYd")
		)
		(fp_rect
			(start -0.381 0.7366)
			(end 0.381 -0.7366)
			(stroke
				(width 0)
				(type default)
			)
			(fill no)
			(layer "F.Fab")
		)
		(pad "1" smd custom
			(at 0 -0.4572 90)
			(size 0.1143 0.1143)
			(layers "F.Cu" "F.Mask" "F.Paste")
			(net "VR_PVDDR_A_COMP")
			(options
				(clearance outline)
				(anchor circle)
			)
			(primitives
				(gr_poly
					(pts
						(arc
							(start -0.254 -0.1778)
							(mid -0.239121 -0.213721)
							(end -0.2032 -0.2286)
						)
						(arc
							(start 0.2032 -0.2286)
							(mid 0.239121 -0.213721)
							(end 0.254 -0.1778)
						)
						(arc
							(start 0.254 0.1778)
							(mid 0.239121 0.213721)
							(end 0.2032 0.2286)
						)
						(arc
							(start -0.2032 0.2286)
							(mid -0.239121 0.213721)
							(end -0.254 0.1778)
						)
					)
					(width 0)
					(fill yes)
				)
			)
		)
		(pad "2" smd custom
			(at 0 0.4572 90)
			(size 0.1143 0.1143)
			(layers "F.Cu" "F.Mask" "F.Paste")
			(net "VR_PVDDR_A_FB_COMP")
			(options
				(clearance outline)
				(anchor circle)
			)
			(primitives
				(gr_poly
					(pts
						(arc
							(start -0.254 -0.1778)
							(mid -0.239121 -0.213721)
							(end -0.2032 -0.2286)
						)
						(arc
							(start 0.2032 -0.2286)
							(mid 0.239121 -0.213721)
							(end 0.254 -0.1778)
						)
						(arc
							(start 0.254 0.1778)
							(mid 0.239121 0.213721)
							(end 0.2032 0.2286)
						)
						(arc
							(start -0.2032 0.2286)
							(mid -0.239121 0.213721)
							(end -0.254 0.1778)
						)
					)
					(width 0)
					(fill yes)
				)
			)
		)
	)
	(footprint ""
		(layer "F.Cu")
		(at 8.509 -63.627 90)
		(property "Reference" "C189"
			(at 0 0 90)
			(layer "F.SilkS")
			(hide yes)
			(effects
				(font
					(size 1.27 1.27)
				)
			)
		)
		(property "Value" "SCD1U16V2KX-3GP"
			(at 1.1811 -2.7051 90)
			(unlocked yes)
			(layer "F.Fab")
			(hide yes)
			(effects
				(font
					(size 1.016 1.016)
					(thickness 0.1524)
				)
			)
		)
		(property "Device Type" "C402H22"
			(at 1.1811 -4.2291 90)
			(unlocked yes)
			(layer "F.Fab")
			(hide yes)
			(effects
				(font
					(size 1.016 1.016)
					(thickness 0.1524)
				)
			)
		)
		(duplicate_pad_numbers_are_jumpers no)
		(fp_rect
			(start -0.381 0.7366)
			(end 0.381 -0.7366)
			(stroke
				(width 0)
				(type default)
			)
			(fill no)
			(layer "F.CrtYd")
		)
		(fp_rect
			(start -0.381 0.7366)
			(end 0.381 -0.7366)
			(stroke
				(width 0)
				(type default)
			)
			(fill no)
			(layer "F.Fab")
		)
		(pad "1" smd custom
			(at 0 -0.4572 90)
			(size 0.1143 0.1143)
			(layers "F.Cu" "F.Mask" "F.Paste")
			(net "P2E_CPU_NGFF_TX_DN15")
			(options
				(clearance outline)
				(anchor circle)
			)
			(primitives
				(gr_poly
					(pts
						(arc
							(start -0.254 -0.1778)
							(mid -0.239121 -0.213721)
							(end -0.2032 -0.2286)
						)
						(arc
							(start 0.2032 -0.2286)
							(mid 0.239121 -0.213721)
							(end 0.254 -0.1778)
						)
						(arc
							(start 0.254 0.1778)
							(mid 0.239121 0.213721)
							(end 0.2032 0.2286)
						)
						(arc
							(start -0.2032 0.2286)
							(mid -0.239121 0.213721)
							(end -0.254 0.1778)
						)
					)
					(width 0)
					(fill yes)
				)
			)
		)
		(pad "2" smd custom
			(at 0 0.4572 90)
			(size 0.1143 0.1143)
			(layers "F.Cu" "F.Mask" "F.Paste")
			(net "P2E_CPU_NGFF_C_TX_DN15")
			(options
				(clearance outline)
				(anchor circle)
			)
			(primitives
				(gr_poly
					(pts
						(arc
							(start -0.254 -0.1778)
							(mid -0.239121 -0.213721)
							(end -0.2032 -0.2286)
						)
						(arc
							(start 0.2032 -0.2286)
							(mid 0.239121 -0.213721)
							(end 0.254 -0.1778)
						)
						(arc
							(start 0.254 0.1778)
							(mid 0.239121 0.213721)
							(end 0.2032 0.2286)
						)
						(arc
							(start -0.2032 0.2286)
							(mid -0.239121 0.213721)
							(end -0.254 0.1778)
						)
					)
					(width 0)
					(fill yes)
				)
			)
		)
	)
	(footprint ""
		(layer "F.Cu")
		(at 59.817 -17.018 90)
		(property "Reference" "R180"
			(at 0 0 90)
			(layer "F.SilkS")
			(hide yes)
			(effects
				(font
					(size 1.27 1.27)
				)
			)
		)
		(property "Value" "0R2J-2-GP"
			(at 0.064008 -3.993896 90)
			(unlocked yes)
			(layer "F.Fab")
			(hide yes)
			(effects
				(font
					(size 1.016 1.016)
					(thickness 0.1524)
				)
			)
		)
		(property "Device Type" "R402H16"
			(at 0.064008 -5.517896 90)
			(unlocked yes)
			(layer "F.Fab")
			(hide yes)
			(effects
				(font
					(size 1.016 1.016)
					(thickness 0.1524)
				)
			)
		)
		(duplicate_pad_numbers_are_jumpers no)
		(fp_rect
			(start -0.381 0.8382)
			(end 0.381 -0.8382)
			(stroke
				(width 0)
				(type default)
			)
			(fill no)
			(layer "F.CrtYd")
		)
		(fp_rect
			(start -0.381 0.8382)
			(end 0.381 -0.8382)
			(stroke
				(width 0)
				(type default)
			)
			(fill no)
			(layer "F.Fab")
		)
		(pad "1" smd custom
			(at 0 -0.4318 90)
			(size 0.127 0.127)
			(layers "F.Cu" "F.Mask" "F.Paste")
			(net "SPI_MOSI_GBE_R")
			(options
				(clearance outline)
				(anchor circle)
			)
			(primitives
				(gr_poly
					(pts
						(arc
							(start -0.2032 -0.2794)
							(mid -0.239121 -0.264521)
							(end -0.254 -0.2286)
						)
						(arc
							(start -0.254 0.2286)
							(mid -0.239121 0.264521)
							(end -0.2032 0.2794)
						)
						(arc
							(start 0.2032 0.2794)
							(mid 0.239121 0.264521)
							(end 0.254 0.2286)
						)
						(arc
							(start 0.254 -0.2286)
							(mid 0.239121 -0.264521)
							(end 0.2032 -0.2794)
						)
					)
					(width 0)
					(fill yes)
				)
			)
		)
		(pad "2" smd custom
			(at 0 0.4318 90)
			(size 0.127 0.127)
			(layers "F.Cu" "F.Mask" "F.Paste")
			(net "SPI_MOSI_GBE")
			(options
				(clearance outline)
				(anchor circle)
			)
			(primitives
				(gr_poly
					(pts
						(arc
							(start -0.2032 -0.2794)
							(mid -0.239121 -0.264521)
							(end -0.254 -0.2286)
						)
						(arc
							(start -0.254 0.2286)
							(mid -0.239121 0.264521)
							(end -0.2032 0.2794)
						)
						(arc
							(start 0.2032 0.2794)
							(mid 0.239121 0.264521)
							(end 0.254 0.2286)
						)
						(arc
							(start 0.254 -0.2286)
							(mid 0.239121 -0.264521)
							(end 0.2032 -0.2794)
						)
					)
					(width 0)
					(fill yes)
				)
			)
		)
	)
	(footprint ""
		(layer "F.Cu")
		(at 19.939 -21.59 90)
		(property "Reference" "PC75"
			(at 0 0 90)
			(layer "F.SilkS")
			(hide yes)
			(effects
				(font
					(size 1.27 1.27)
				)
			)
		)
		(property "Value" "SC1KP50V2KX-1GP"
			(at 1.8923 -1.2065 90)
			(unlocked yes)
			(layer "F.Fab")
			(hide yes)
			(effects
				(font
					(size 1.016 1.016)
					(thickness 0.1524)
				)
			)
		)
		(property "Device Type" "C402H22"
			(at 1.8923 -2.7305 90)
			(unlocked yes)
			(layer "F.Fab")
			(hide yes)
			(effects
				(font
					(size 1.016 1.016)
					(thickness 0.1524)
				)
			)
		)
		(duplicate_pad_numbers_are_jumpers no)
		(fp_rect
			(start -0.381 0.7366)
			(end 0.381 -0.7366)
			(stroke
				(width 0)
				(type default)
			)
			(fill no)
			(layer "F.CrtYd")
		)
		(fp_rect
			(start -0.381 0.7366)
			(end 0.381 -0.7366)
			(stroke
				(width 0)
				(type default)
			)
			(fill no)
			(layer "F.Fab")
		)
		(pad "1" smd custom
			(at 0 -0.4572 90)
			(size 0.1143 0.1143)
			(layers "F.Cu" "F.Mask" "F.Paste")
			(net "P1V0_VFB")
			(options
				(clearance outline)
				(anchor circle)
			)
			(primitives
				(gr_poly
					(pts
						(arc
							(start -0.254 -0.1778)
							(mid -0.239121 -0.213721)
							(end -0.2032 -0.2286)
						)
						(arc
							(start 0.2032 -0.2286)
							(mid 0.239121 -0.213721)
							(end 0.254 -0.1778)
						)
						(arc
							(start 0.254 0.1778)
							(mid 0.239121 0.213721)
							(end 0.2032 0.2286)
						)
						(arc
							(start -0.2032 0.2286)
							(mid -0.239121 0.213721)
							(end -0.254 0.1778)
						)
					)
					(width 0)
					(fill yes)
				)
			)
		)
		(pad "2" smd custom
			(at 0 0.4572 90)
			(size 0.1143 0.1143)
			(layers "F.Cu" "F.Mask" "F.Paste")
			(net "P1V0_SW_R")
			(options
				(clearance outline)
				(anchor circle)
			)
			(primitives
				(gr_poly
					(pts
						(arc
							(start -0.254 -0.1778)
							(mid -0.239121 -0.213721)
							(end -0.2032 -0.2286)
						)
						(arc
							(start 0.2032 -0.2286)
							(mid 0.239121 -0.213721)
							(end 0.254 -0.1778)
						)
						(arc
							(start 0.254 0.1778)
							(mid 0.239121 0.213721)
							(end 0.2032 0.2286)
						)
						(arc
							(start -0.2032 0.2286)
							(mid -0.239121 0.213721)
							(end -0.254 0.1778)
						)
					)
					(width 0)
					(fill yes)
				)
			)
		)
	)
	(footprint ""
		(layer "F.Cu")
		(at 197.739 -1.778 90)
		(property "Reference" "C91"
			(at 0 0 90)
			(layer "F.SilkS")
			(hide yes)
			(effects
				(font
					(size 1.27 1.27)
				)
			)
		)
		(property "Value" "SC10U6D3V3MX-GP"
			(at 0 -2.8194 90)
			(unlocked yes)
			(layer "F.Fab")
			(hide yes)
			(effects
				(font
					(size 1.016 1.016)
					(thickness 0.1524)
				)
			)
		)
		(property "Device Type" "C603H38"
			(at 0 -4.3434 90)
			(unlocked yes)
			(layer "F.Fab")
			(hide yes)
			(effects
				(font
					(size 1.016 1.016)
					(thickness 0.1524)
				)
			)
		)
		(duplicate_pad_numbers_are_jumpers no)
		(fp_line
			(start -0.4064 0)
			(end 0.4064 0)
			(stroke
				(width 0.2286)
				(type default)
			)
			(layer "F.SilkS")
		)
		(fp_rect
			(start -0.635 1.1811)
			(end 0.635 -1.1811)
			(stroke
				(width 0)
				(type default)
			)
			(fill no)
			(layer "F.CrtYd")
		)
		(fp_rect
			(start -0.635 1.1811)
			(end 0.635 -1.1811)
			(stroke
				(width 0)
				(type default)
			)
			(fill no)
			(layer "F.Fab")
		)
		(pad "1" smd custom
			(at 0 -0.6604 90)
			(size 0.19685 0.19685)
			(layers "F.Cu" "F.Mask" "F.Paste")
			(net "PV_VTT_DDR_B")
			(options
				(clearance outline)
				(anchor circle)
			)
			(primitives
				(gr_poly
					(pts
						(arc
							(start 0.508 -0.2921)
							(mid 0.478242 -0.363942)
							(end 0.4064 -0.3937)
						)
						(arc
							(start -0.4064 -0.3937)
							(mid -0.478242 -0.363942)
							(end -0.508 -0.2921)
						)
						(arc
							(start -0.508 0.2921)
							(mid -0.478242 0.363942)
							(end -0.4064 0.3937)
						)
						(arc
							(start 0.4064 0.3937)
							(mid 0.478242 0.363942)
							(end 0.508 0.2921)
						)
					)
					(width 0)
					(fill yes)
				)
			)
		)
		(pad "2" smd custom
			(at 0 0.6604 90)
			(size 0.19685 0.19685)
			(layers "F.Cu" "F.Mask" "F.Paste")
			(net "GND")
			(options
				(clearance outline)
				(anchor circle)
			)
			(primitives
				(gr_poly
					(pts
						(arc
							(start 0.508 -0.2921)
							(mid 0.478242 -0.363942)
							(end 0.4064 -0.3937)
						)
						(arc
							(start -0.4064 -0.3937)
							(mid -0.478242 -0.363942)
							(end -0.508 -0.2921)
						)
						(arc
							(start -0.508 0.2921)
							(mid -0.478242 0.363942)
							(end -0.4064 0.3937)
						)
						(arc
							(start 0.4064 0.3937)
							(mid 0.478242 0.363942)
							(end 0.508 0.2921)
						)
					)
					(width 0)
					(fill yes)
				)
			)
		)
	)
)
